# T6G (Grand Teton) — schematic netlist excerpt (pin names and nets, part order shuffled) for the footprints in the layout excerpt that follows; sources: Cadence DE-HDL packaged netlist, KiCad conversion of 04192023_DAF0TMB3IC0_F0TG_MB_C_brd_V02_OCP.brd

R2587  Q_RES  1K 1% CHIP  pkg 0402LF  page 262 : A = IRQ_HSC_FAULT_N ; B = HSC_VDD
R2995  Q_RES  33.2 1% CHIP  pkg 0402LF  page 151 : A = SMB_PMBUS_3V3AUX_SCL ; B = SMB_SML1_PMBUS_HSC_SCL

(kicad_pcb
	(version 20260206)
	(generator "pcbnew")
	(generator_version "10.0")
	(general
		(thickness 1.6)
		(legacy_teardrops no)
	)
	(paper "A4")
	(title_block
		(title "04192023_DAF0TMB3IC0_F0TG_MB_C_brd_V02_OCP.brd")
		(comment 1 "Grand Teton / footprints 7898-7899 of 8354")
	)
	(layers
		(0 "F.Cu" signal "TOP")
		(4 "In1.Cu" signal "GND")
		(6 "In2.Cu" signal "IN1")
		(8 "In3.Cu" signal "GND1")
		(10 "In4.Cu" signal "IN2")
		(12 "In5.Cu" signal "GND2")
		(14 "In6.Cu" signal "IN3")
		(16 "In7.Cu" signal "GND3")
		(18 "In8.Cu" signal "VCC")
		(20 "In9.Cu" signal "VCC1")
		(22 "In10.Cu" signal "GND4")
		(24 "In11.Cu" signal "IN4")
		(26 "In12.Cu" signal "GND5")
		(28 "In13.Cu" signal "IN5")
		(30 "In14.Cu" signal "GND6")
		(32 "In15.Cu" signal "IN6")
		(34 "In16.Cu" signal "GND7")
		(2 "B.Cu" signal "BOTTOM")
		(9 "F.Adhes" user "F.Adhesive")
		(11 "B.Adhes" user "B.Adhesive")
		(13 "F.Paste" user "Package Geometry/Pastemask Top")
		(15 "B.Paste" user "Package Geometry/Pastemask Bottom")
		(5 "F.SilkS" user "Ref Des/Silkscreen Top")
		(7 "B.SilkS" user "Ref Des/Silkscreen Bottom")
		(1 "F.Mask" user "Board Geometry/Soldermask Top")
		(3 "B.Mask" user "Board Geometry/Soldermask Bottom")
		(17 "Dwgs.User" user "User.Drawings")
		(19 "Cmts.User" user "User.Comments")
		(21 "Eco1.User" user "User.Eco1")
		(23 "Eco2.User" user "User.Eco2")
		(25 "Edge.Cuts" user "Board Geometry/Outline")
		(27 "Margin" user)
		(31 "F.CrtYd" user "Package Geometry/Place Bound Top")
		(29 "B.CrtYd" user "Package Geometry/Place Bound Bottom")
		(35 "F.Fab" user "Ref Des/Assembly Top")
		(33 "B.Fab" user "Ref Des/Assembly Bottom")
	)
	(footprint ""
		(layer "B.Cu")
		(at 191.26454 -402.741892 90)
		(property "Reference" "R2587"
			(at 0 0 90)
			(layer "B.SilkS")
			(hide yes)
			(effects
				(font
					(size 1.27 1.27)
				)
				(justify mirror)
			)
		)
		(property "Value" ""
			(at 0 0 90)
			(layer "B.Fab")
			(effects
				(font
					(size 1.27 1.27)
				)
				(justify mirror)
			)
		)
		(duplicate_pad_numbers_are_jumpers no)
		(fp_line
			(start 0.7874 -0.4064)
			(end -0.7874 -0.4064)
			(stroke
				(width 0.1524)
				(type default)
			)
			(layer "B.SilkS")
		)
		(fp_line
			(start -0.7874 -0.4064)
			(end -0.7874 0.4064)
			(stroke
				(width 0.1524)
				(type default)
			)
			(layer "B.SilkS")
		)
		(fp_line
			(start 0.7874 0.4064)
			(end 0.7874 -0.4064)
			(stroke
				(width 0.1524)
				(type default)
			)
			(layer "B.SilkS")
		)
		(fp_line
			(start -0.7874 0.4064)
			(end 0.7874 0.4064)
			(stroke
				(width 0.1524)
				(type default)
			)
			(layer "B.SilkS")
		)
		(fp_line
			(start 0.67945 -0.305054)
			(end 0.12065 -0.305054)
			(stroke
				(width 0.1)
				(type default)
			)
			(layer "B.Fab")
		)
		(fp_line
			(start 0.12065 -0.305054)
			(end 0.12065 -0.2794)
			(stroke
				(width 0.1)
				(type default)
			)
			(layer "B.Fab")
		)
		(fp_line
			(start -0.12065 -0.3048)
			(end -0.67945 -0.3048)
			(stroke
				(width 0.1)
				(type default)
			)
			(layer "B.Fab")
		)
		(fp_line
			(start -0.67945 -0.3048)
			(end -0.67945 0.3048)
			(stroke
				(width 0.1)
				(type default)
			)
			(layer "B.Fab")
		)
		(fp_line
			(start 0.12065 -0.2794)
			(end -0.12065 -0.2794)
			(stroke
				(width 0.1)
				(type default)
			)
			(layer "B.Fab")
		)
		(fp_line
			(start -0.12065 -0.2794)
			(end -0.12065 -0.3048)
			(stroke
				(width 0.1)
				(type default)
			)
			(layer "B.Fab")
		)
		(fp_line
			(start 0.12065 0.2794)
			(end 0.12065 0.3048)
			(stroke
				(width 0.1)
				(type default)
			)
			(layer "B.Fab")
		)
		(fp_line
			(start -0.120396 0.2794)
			(end 0.12065 0.2794)
			(stroke
				(width 0.1)
				(type default)
			)
			(layer "B.Fab")
		)
		(fp_line
			(start 0.67945 0.3048)
			(end 0.67945 -0.305054)
			(stroke
				(width 0.1)
				(type default)
			)
			(layer "B.Fab")
		)
		(fp_line
			(start 0.12065 0.3048)
			(end 0.67945 0.3048)
			(stroke
				(width 0.1)
				(type default)
			)
			(layer "B.Fab")
		)
		(fp_line
			(start -0.120396 0.3048)
			(end -0.120396 0.2794)
			(stroke
				(width 0.1)
				(type default)
			)
			(layer "B.Fab")
		)
		(fp_line
			(start -0.67945 0.3048)
			(end -0.120396 0.3048)
			(stroke
				(width 0.1)
				(type default)
			)
			(layer "B.Fab")
		)
		(pad "1" smd circle
			(at 0.40005 0 270)
			(size 0 0)
			(layers "B.Cu" "B.Mask" "B.Paste")
			(net "IRQ_HSC_FAULT_N")
		)
		(pad "2" smd circle
			(at -0.40005 0 270)
			(size 0 0)
			(layers "B.Cu" "B.Mask" "B.Paste")
			(net "HSC_VDD")
		)
	)
	(footprint ""
		(layer "B.Cu")
		(at 167.31869 -14.462506 -90)
		(property "Reference" "R2995"
			(at 0 0 90)
			(layer "B.SilkS")
			(hide yes)
			(effects
				(font
					(size 1.27 1.27)
				)
				(justify mirror)
			)
		)
		(property "Value" ""
			(at 0 0 90)
			(layer "B.Fab")
			(effects
				(font
					(size 1.27 1.27)
				)
				(justify mirror)
			)
		)
		(duplicate_pad_numbers_are_jumpers no)
		(fp_line
			(start -0.7874 0.4064)
			(end 0.7874 0.4064)
			(stroke
				(width 0.1524)
				(type default)
			)
			(layer "B.SilkS")
		)
		(fp_line
			(start 0.7874 0.4064)
			(end 0.7874 -0.4064)
			(stroke
				(width 0.1524)
				(type default)
			)
			(layer "B.SilkS")
		)
		(fp_line
			(start -0.7874 -0.4064)
			(end -0.7874 0.4064)
			(stroke
				(width 0.1524)
				(type default)
			)
			(layer "B.SilkS")
		)
		(fp_line
			(start 0.7874 -0.4064)
			(end -0.7874 -0.4064)
			(stroke
				(width 0.1524)
				(type default)
			)
			(layer "B.SilkS")
		)
		(fp_line
			(start -0.67945 0.3048)
			(end -0.120396 0.3048)
			(stroke
				(width 0.1)
				(type default)
			)
			(layer "B.Fab")
		)
		(fp_line
			(start -0.120396 0.3048)
			(end -0.120396 0.2794)
			(stroke
				(width 0.1)
				(type default)
			)
			(layer "B.Fab")
		)
		(fp_line
			(start 0.12065 0.3048)
			(end 0.67945 0.3048)
			(stroke
				(width 0.1)
				(type default)
			)
			(layer "B.Fab")
		)
		(fp_line
			(start 0.67945 0.3048)
			(end 0.67945 -0.305054)
			(stroke
				(width 0.1)
				(type default)
			)
			(layer "B.Fab")
		)
		(fp_line
			(start -0.120396 0.2794)
			(end 0.12065 0.2794)
			(stroke
				(width 0.1)
				(type default)
			)
			(layer "B.Fab")
		)
		(fp_line
			(start 0.12065 0.2794)
			(end 0.12065 0.3048)
			(stroke
				(width 0.1)
				(type default)
			)
			(layer "B.Fab")
		)
		(fp_line
			(start -0.12065 -0.2794)
			(end -0.12065 -0.3048)
			(stroke
				(width 0.1)
				(type default)
			)
			(layer "B.Fab")
		)
		(fp_line
			(start 0.12065 -0.2794)
			(end -0.12065 -0.2794)
			(stroke
				(width 0.1)
				(type default)
			)
			(layer "B.Fab")
		)
		(fp_line
			(start -0.67945 -0.3048)
			(end -0.67945 0.3048)
			(stroke
				(width 0.1)
				(type default)
			)
			(layer "B.Fab")
		)
		(fp_line
			(start -0.12065 -0.3048)
			(end -0.67945 -0.3048)
			(stroke
				(width 0.1)
				(type default)
			)
			(layer "B.Fab")
		)
		(fp_line
			(start 0.12065 -0.305054)
			(end 0.12065 -0.2794)
			(stroke
				(width 0.1)
				(type default)
			)
			(layer "B.Fab")
		)
		(fp_line
			(start 0.67945 -0.305054)
			(end 0.12065 -0.305054)
			(stroke
				(width 0.1)
				(type default)
			)
			(layer "B.Fab")
		)
		(pad "1" smd circle
			(at 0.40005 0 90)
			(size 0 0)
			(layers "B.Cu" "B.Mask" "B.Paste")
			(net "SMB_PMBUS_3V3AUX_SCL")
		)
		(pad "2" smd circle
			(at -0.40005 0 90)
			(size 0 0)
			(layers "B.Cu" "B.Mask" "B.Paste")
			(net "SMB_SML1_PMBUS_HSC_SCL")
		)
	)
)
